(kicad_pcb
	(version 20260206)
	(generator "pcbnew")
	(generator_version "10.0")
	(general
		(thickness 1.6)
		(legacy_teardrops no)
	)
	(paper "A4")
	(title_block
		(title "baseboard — 13948-1b.1110WZS1818.brd")
		(comment 1 "Honey Badger (Wiwynn) / footprints 1838-1846 of 2523")
	)
	(layers
		(0 "F.Cu" signal "TOP")
		(4 "In1.Cu" signal "L2GND")
		(6 "In2.Cu" signal "L3")
		(8 "In3.Cu" signal "L4VCC")
		(10 "In4.Cu" signal "L5VCC")
		(12 "In5.Cu" signal "L6")
		(14 "In6.Cu" signal "L7GND")
		(2 "B.Cu" signal "BOTTOM")
		(9 "F.Adhes" user "F.Adhesive")
		(11 "B.Adhes" user "B.Adhesive")
		(13 "F.Paste" user "Package Geometry/Pastemask Top")
		(15 "B.Paste" user "Package Geometry/Pastemask Bottom")
		(5 "F.SilkS" user "Ref Des/Silkscreen Top")
		(7 "B.SilkS" user "Ref Des/Silkscreen Bottom")
		(1 "F.Mask" user "Board Geometry/Soldermask Top")
		(3 "B.Mask" user "Board Geometry/Soldermask Bottom")
		(17 "Dwgs.User" user "User.Drawings")
		(19 "Cmts.User" user "User.Comments")
		(21 "Eco1.User" user "User.Eco1")
		(23 "Eco2.User" user "User.Eco2")
		(25 "Edge.Cuts" user "Board Geometry/Outline")
		(27 "Margin" user)
		(31 "F.CrtYd" user "Package Geometry/Place Bound Top")
		(29 "B.CrtYd" user "Package Geometry/Place Bound Bottom")
		(35 "F.Fab" user "Ref Des/Assembly Top")
		(33 "B.Fab" user "Ref Des/Assembly Bottom")
	)
	(footprint ""
		(layer "B.Cu")
		(at 111.29137 -97.5106 90)
		(property "Reference" "SC1255"
			(at 0 0 90)
			(layer "B.SilkS")
			(hide yes)
			(effects
				(font
					(size 1.27 1.27)
				)
				(justify mirror)
			)
		)
		(property "Value" "SCD1U6D3V1KX-GP"
			(at 2.8321 -1.7399 90)
			(unlocked yes)
			(layer "B.Fab")
			(hide yes)
			(effects
				(font
					(size 1.016 1.016)
					(thickness 0.1524)
				)
				(justify mirror)
			)
		)
		(property "Device Type" "C0201H13"
			(at 2.8321 -3.2639 90)
			(unlocked yes)
			(layer "B.Fab")
			(hide yes)
			(effects
				(font
					(size 1.016 1.016)
					(thickness 0.1524)
				)
				(justify mirror)
			)
		)
		(duplicate_pad_numbers_are_jumpers no)
		(fp_rect
			(start 0.2794 0.6477)
			(end -0.2794 -0.6477)
			(stroke
				(width 0)
				(type default)
			)
			(fill no)
			(layer "B.CrtYd")
		)
		(fp_rect
			(start 0.2794 0.6477)
			(end -0.2794 -0.6477)
			(stroke
				(width 0)
				(type default)
			)
			(fill no)
			(layer "B.Fab")
		)
		(pad "1" smd custom
			(at 0 -0.2794 270)
			(size 0.0762 0.0762)
			(layers "B.Cu" "B.Mask" "B.Paste")
			(net "P0V9_E")
			(options
				(clearance outline)
				(anchor circle)
			)
			(primitives
				(gr_poly
					(pts
						(arc
							(start 0.1524 0.127)
							(mid 0.137521 0.162921)
							(end 0.1016 0.1778)
						)
						(arc
							(start -0.1016 0.1778)
							(mid -0.137521 0.162921)
							(end -0.1524 0.127)
						)
						(arc
							(start -0.1524 -0.127)
							(mid -0.137521 -0.162921)
							(end -0.1016 -0.1778)
						)
						(arc
							(start 0.1016 -0.1778)
							(mid 0.137521 -0.162921)
							(end 0.1524 -0.127)
						)
					)
					(width 0)
					(fill yes)
				)
			)
		)
		(pad "2" smd custom
			(at 0 0.2794 270)
			(size 0.0762 0.0762)
			(layers "B.Cu" "B.Mask" "B.Paste")
			(net "GND")
			(options
				(clearance outline)
				(anchor circle)
			)
			(primitives
				(gr_poly
					(pts
						(arc
							(start 0.1524 0.127)
							(mid 0.137521 0.162921)
							(end 0.1016 0.1778)
						)
						(arc
							(start -0.1016 0.1778)
							(mid -0.137521 0.162921)
							(end -0.1524 0.127)
						)
						(arc
							(start -0.1524 -0.127)
							(mid -0.137521 -0.162921)
							(end -0.1016 -0.1778)
						)
						(arc
							(start 0.1016 -0.1778)
							(mid 0.137521 -0.162921)
							(end 0.1524 -0.127)
						)
					)
					(width 0)
					(fill yes)
				)
			)
		)
	)
	(footprint ""
		(layer "B.Cu")
		(at 107.07116 -30.099)
		(property "Reference" "STP115"
			(at 0 0 0)
			(layer "B.SilkS")
			(hide yes)
			(effects
				(font
					(size 1.27 1.27)
				)
				(justify mirror)
			)
		)
		(property "Value" "TPAD28"
			(at -0.0127 -1.8034 0)
			(unlocked yes)
			(layer "B.Fab")
			(hide yes)
			(effects
				(font
					(size 1.016 1.016)
					(thickness 0.1524)
				)
				(justify mirror)
			)
		)
		(property "Device Type" "TPAD28"
			(at -0.0127 -3.3274 0)
			(unlocked yes)
			(layer "B.Fab")
			(hide yes)
			(effects
				(font
					(size 1.016 1.016)
					(thickness 0.1524)
				)
				(justify mirror)
			)
		)
		(duplicate_pad_numbers_are_jumpers no)
		(fp_poly
			(pts
				(arc
					(start 0.3556 0)
					(mid -0.3556 0)
					(end 0.3556 0)
				)
			)
			(stroke
				(width 0)
				(type default)
			)
			(fill no)
			(layer "B.CrtYd")
		)
		(fp_poly
			(pts
				(arc
					(start 0.6096 0)
					(mid -0.6096 0)
					(end 0.6096 0)
				)
			)
			(stroke
				(width 0)
				(type default)
			)
			(fill no)
			(layer "B.Fab")
		)
		(pad "1" smd circle
			(at 0 0 180)
			(size 0.7112 0.7112)
			(layers "B.Cu" "B.Mask" "B.Paste")
			(net "SYS_ERROR1")
		)
	)
	(footprint ""
		(layer "B.Cu")
		(at 115.437666 -38.1381)
		(property "Reference" "STP8"
			(at 0 0 0)
			(layer "B.SilkS")
			(hide yes)
			(effects
				(font
					(size 1.27 1.27)
				)
				(justify mirror)
			)
		)
		(property "Value" "TPAD28"
			(at -0.0127 -1.8034 0)
			(unlocked yes)
			(layer "B.Fab")
			(hide yes)
			(effects
				(font
					(size 1.016 1.016)
					(thickness 0.1524)
				)
				(justify mirror)
			)
		)
		(property "Device Type" "TPAD28"
			(at -0.0127 -3.3274 0)
			(unlocked yes)
			(layer "B.Fab")
			(hide yes)
			(effects
				(font
					(size 1.016 1.016)
					(thickness 0.1524)
				)
				(justify mirror)
			)
		)
		(duplicate_pad_numbers_are_jumpers no)
		(fp_poly
			(pts
				(arc
					(start 0.3556 0)
					(mid -0.3556 0)
					(end 0.3556 0)
				)
			)
			(stroke
				(width 0)
				(type default)
			)
			(fill no)
			(layer "B.CrtYd")
		)
		(fp_poly
			(pts
				(arc
					(start 0.6096 0)
					(mid -0.6096 0)
					(end 0.6096 0)
				)
			)
			(stroke
				(width 0)
				(type default)
			)
			(fill no)
			(layer "B.Fab")
		)
		(pad "1" smd circle
			(at 0 0 180)
			(size 0.7112 0.7112)
			(layers "B.Cu" "B.Mask" "B.Paste")
			(net "IOC_GPIO_28")
		)
	)
	(footprint ""
		(layer "B.Cu")
		(at 118.872 -44.704 -90)
		(property "Reference" "SR617"
			(at 0 0 90)
			(layer "B.SilkS")
			(hide yes)
			(effects
				(font
					(size 1.27 1.27)
				)
				(justify mirror)
			)
		)
		(property "Value" "2K2R2F-GP"
			(at -0.064008 -3.993896 270)
			(unlocked yes)
			(layer "B.Fab")
			(hide yes)
			(effects
				(font
					(size 1.016 1.016)
					(thickness 0.1524)
				)
				(justify mirror)
			)
		)
		(property "Device Type" "R402H16"
			(at -0.064008 -5.517896 270)
			(unlocked yes)
			(layer "B.Fab")
			(hide yes)
			(effects
				(font
					(size 1.016 1.016)
					(thickness 0.1524)
				)
				(justify mirror)
			)
		)
		(duplicate_pad_numbers_are_jumpers no)
		(fp_line
			(start -0.508 -0.9398)
			(end 0.508 -0.9398)
			(stroke
				(width 0.1524)
				(type default)
			)
			(layer "B.SilkS")
		)
		(fp_line
			(start 0.508 -0.9398)
			(end 0.508 0.9398)
			(stroke
				(width 0.1524)
				(type default)
			)
			(layer "B.SilkS")
		)
		(fp_rect
			(start 0.508 0.9398)
			(end -0.508 -0.9398)
			(stroke
				(width 0)
				(type default)
			)
			(fill no)
			(layer "B.CrtYd")
		)
		(fp_rect
			(start 0.508 0.9398)
			(end -0.508 -0.9398)
			(stroke
				(width 0)
				(type default)
			)
			(fill no)
			(layer "B.Fab")
		)
		(pad "1" smd custom
			(at 0 -0.4445 90)
			(size 0.1397 0.1397)
			(layers "B.Cu" "B.Mask" "B.Paste")
			(net "P1V8_C")
			(options
				(clearance outline)
				(anchor circle)
			)
			(primitives
				(gr_poly
					(pts
						(arc
							(start -0.1778 0.2794)
							(mid -0.249642 0.249642)
							(end -0.2794 0.1778)
						)
						(arc
							(start -0.2794 -0.1778)
							(mid -0.249642 -0.249642)
							(end -0.1778 -0.2794)
						)
						(arc
							(start 0.1778 -0.2794)
							(mid 0.249642 -0.249642)
							(end 0.2794 -0.1778)
						)
						(arc
							(start 0.2794 0.1778)
							(mid 0.249642 0.249642)
							(end 0.1778 0.2794)
						)
					)
					(width 0)
					(fill yes)
				)
			)
		)
		(pad "2" smd custom
			(at 0 0.4445 90)
			(size 0.1397 0.1397)
			(layers "B.Cu" "B.Mask" "B.Paste")
			(net "IOC_SDA_0")
			(options
				(clearance outline)
				(anchor circle)
			)
			(primitives
				(gr_poly
					(pts
						(arc
							(start -0.1778 0.2794)
							(mid -0.249642 0.249642)
							(end -0.2794 0.1778)
						)
						(arc
							(start -0.2794 -0.1778)
							(mid -0.249642 -0.249642)
							(end -0.1778 -0.2794)
						)
						(arc
							(start 0.1778 -0.2794)
							(mid 0.249642 -0.249642)
							(end 0.2794 -0.1778)
						)
						(arc
							(start 0.2794 0.1778)
							(mid 0.249642 0.249642)
							(end 0.1778 0.2794)
						)
					)
					(width 0)
					(fill yes)
				)
			)
		)
	)
	(footprint ""
		(layer "B.Cu")
		(at 119.13997 -105.918 180)
		(property "Reference" "SC1163"
			(at 0 0 0)
			(layer "B.SilkS")
			(hide yes)
			(effects
				(font
					(size 1.27 1.27)
				)
				(justify mirror)
			)
		)
		(property "Value" "SCD1U6D3V1KX-GP"
			(at 2.8321 -1.7399 180)
			(unlocked yes)
			(layer "B.Fab")
			(hide yes)
			(effects
				(font
					(size 1.016 1.016)
					(thickness 0.1524)
				)
				(justify mirror)
			)
		)
		(property "Device Type" "C0201H13"
			(at 2.8321 -3.2639 180)
			(unlocked yes)
			(layer "B.Fab")
			(hide yes)
			(effects
				(font
					(size 1.016 1.016)
					(thickness 0.1524)
				)
				(justify mirror)
			)
		)
		(duplicate_pad_numbers_are_jumpers no)
		(fp_rect
			(start 0.2794 0.6477)
			(end -0.2794 -0.6477)
			(stroke
				(width 0)
				(type default)
			)
			(fill no)
			(layer "B.CrtYd")
		)
		(fp_rect
			(start 0.2794 0.6477)
			(end -0.2794 -0.6477)
			(stroke
				(width 0)
				(type default)
			)
			(fill no)
			(layer "B.Fab")
		)
		(pad "1" smd custom
			(at 0 -0.2794)
			(size 0.0762 0.0762)
			(layers "B.Cu" "B.Mask" "B.Paste")
			(net "GB_VDDA")
			(options
				(clearance outline)
				(anchor circle)
			)
			(primitives
				(gr_poly
					(pts
						(arc
							(start 0.1524 0.127)
							(mid 0.137521 0.162921)
							(end 0.1016 0.1778)
						)
						(arc
							(start -0.1016 0.1778)
							(mid -0.137521 0.162921)
							(end -0.1524 0.127)
						)
						(arc
							(start -0.1524 -0.127)
							(mid -0.137521 -0.162921)
							(end -0.1016 -0.1778)
						)
						(arc
							(start 0.1016 -0.1778)
							(mid 0.137521 -0.162921)
							(end 0.1524 -0.127)
						)
					)
					(width 0)
					(fill yes)
				)
			)
		)
		(pad "2" smd custom
			(at 0 0.2794)
			(size 0.0762 0.0762)
			(layers "B.Cu" "B.Mask" "B.Paste")
			(net "GND")
			(options
				(clearance outline)
				(anchor circle)
			)
			(primitives
				(gr_poly
					(pts
						(arc
							(start 0.1524 0.127)
							(mid 0.137521 0.162921)
							(end 0.1016 0.1778)
						)
						(arc
							(start -0.1016 0.1778)
							(mid -0.137521 0.162921)
							(end -0.1524 0.127)
						)
						(arc
							(start -0.1524 -0.127)
							(mid -0.137521 -0.162921)
							(end -0.1016 -0.1778)
						)
						(arc
							(start 0.1016 -0.1778)
							(mid 0.137521 -0.162921)
							(end 0.1524 -0.127)
						)
					)
					(width 0)
					(fill yes)
				)
			)
		)
	)
	(footprint ""
		(layer "B.Cu")
		(at 121.417842 -84.907882 90)
		(property "Reference" "SR802"
			(at 0 0 90)
			(layer "B.SilkS")
			(hide yes)
			(effects
				(font
					(size 1.27 1.27)
				)
				(justify mirror)
			)
		)
		(property "Value" "4K75R2F-1-GP"
			(at -0.064008 -3.993896 90)
			(unlocked yes)
			(layer "B.Fab")
			(hide yes)
			(effects
				(font
					(size 1.016 1.016)
					(thickness 0.1524)
				)
				(justify mirror)
			)
		)
		(property "Device Type" "R402H16"
			(at -0.064008 -5.517896 90)
			(unlocked yes)
			(layer "B.Fab")
			(hide yes)
			(effects
				(font
					(size 1.016 1.016)
					(thickness 0.1524)
				)
				(justify mirror)
			)
		)
		(duplicate_pad_numbers_are_jumpers no)
		(fp_line
			(start 0.508 -0.9398)
			(end 0.508 0.9398)
			(stroke
				(width 0.1524)
				(type default)
			)
			(layer "B.SilkS")
		)
		(fp_line
			(start -0.508 -0.9398)
			(end 0.508 -0.9398)
			(stroke
				(width 0.1524)
				(type default)
			)
			(layer "B.SilkS")
		)
		(fp_rect
			(start 0.508 0.9398)
			(end -0.508 -0.9398)
			(stroke
				(width 0)
				(type default)
			)
			(fill no)
			(layer "B.CrtYd")
		)
		(fp_rect
			(start 0.508 0.9398)
			(end -0.508 -0.9398)
			(stroke
				(width 0)
				(type default)
			)
			(fill no)
			(layer "B.Fab")
		)
		(pad "1" smd custom
			(at 0 -0.4445 270)
			(size 0.1397 0.1397)
			(layers "B.Cu" "B.Mask" "B.Paste")
			(net "TEST_MUX_47")
			(options
				(clearance outline)
				(anchor circle)
			)
			(primitives
				(gr_poly
					(pts
						(arc
							(start -0.1778 0.2794)
							(mid -0.249642 0.249642)
							(end -0.2794 0.1778)
						)
						(arc
							(start -0.2794 -0.1778)
							(mid -0.249642 -0.249642)
							(end -0.1778 -0.2794)
						)
						(arc
							(start 0.1778 -0.2794)
							(mid 0.249642 -0.249642)
							(end 0.2794 -0.1778)
						)
						(arc
							(start 0.2794 0.1778)
							(mid 0.249642 0.249642)
							(end 0.1778 0.2794)
						)
					)
					(width 0)
					(fill yes)
				)
			)
		)
		(pad "2" smd custom
			(at 0 0.4445 270)
			(size 0.1397 0.1397)
			(layers "B.Cu" "B.Mask" "B.Paste")
			(net "GND")
			(options
				(clearance outline)
				(anchor circle)
			)
			(primitives
				(gr_poly
					(pts
						(arc
							(start -0.1778 0.2794)
							(mid -0.249642 0.249642)
							(end -0.2794 0.1778)
						)
						(arc
							(start -0.2794 -0.1778)
							(mid -0.249642 -0.249642)
							(end -0.1778 -0.2794)
						)
						(arc
							(start 0.1778 -0.2794)
							(mid 0.249642 -0.249642)
							(end 0.2794 -0.1778)
						)
						(arc
							(start 0.2794 0.1778)
							(mid 0.249642 0.249642)
							(end 0.1778 0.2794)
						)
					)
					(width 0)
					(fill yes)
				)
			)
		)
	)
	(footprint ""
		(layer "B.Cu")
		(at 294.132 -164.211 180)
		(property "Reference" "R287"
			(at 0 0 0)
			(layer "B.SilkS")
			(hide yes)
			(effects
				(font
					(size 1.27 1.27)
				)
				(justify mirror)
			)
		)
		(property "Value" "0R2J-2-GP"
			(at -0.064008 -3.993896 180)
			(unlocked yes)
			(layer "B.Fab")
			(hide yes)
			(effects
				(font
					(size 1.016 1.016)
					(thickness 0.1524)
				)
				(justify mirror)
			)
		)
		(property "Device Type" "R402H16"
			(at -0.064008 -5.517896 180)
			(unlocked yes)
			(layer "B.Fab")
			(hide yes)
			(effects
				(font
					(size 1.016 1.016)
					(thickness 0.1524)
				)
				(justify mirror)
			)
		)
		(duplicate_pad_numbers_are_jumpers no)
		(fp_line
			(start 0.508 -0.9398)
			(end 0.508 0.9398)
			(stroke
				(width 0.1524)
				(type default)
			)
			(layer "B.SilkS")
		)
		(fp_line
			(start -0.508 -0.9398)
			(end 0.508 -0.9398)
			(stroke
				(width 0.1524)
				(type default)
			)
			(layer "B.SilkS")
		)
		(fp_rect
			(start 0.508 0.9398)
			(end -0.508 -0.9398)
			(stroke
				(width 0)
				(type default)
			)
			(fill no)
			(layer "B.CrtYd")
		)
		(fp_rect
			(start 0.508 0.9398)
			(end -0.508 -0.9398)
			(stroke
				(width 0)
				(type default)
			)
			(fill no)
			(layer "B.Fab")
		)
		(pad "1" smd custom
			(at 0 -0.4445)
			(size 0.1397 0.1397)
			(layers "B.Cu" "B.Mask" "B.Paste")
			(net "RMII_BMC_RX_ER")
			(options
				(clearance outline)
				(anchor circle)
			)
			(primitives
				(gr_poly
					(pts
						(arc
							(start -0.1778 0.2794)
							(mid -0.249642 0.249642)
							(end -0.2794 0.1778)
						)
						(arc
							(start -0.2794 -0.1778)
							(mid -0.249642 -0.249642)
							(end -0.1778 -0.2794)
						)
						(arc
							(start 0.1778 -0.2794)
							(mid 0.249642 -0.249642)
							(end 0.2794 -0.1778)
						)
						(arc
							(start 0.2794 0.1778)
							(mid 0.249642 0.249642)
							(end 0.1778 0.2794)
						)
					)
					(width 0)
					(fill yes)
				)
			)
		)
		(pad "2" smd custom
			(at 0 0.4445)
			(size 0.1397 0.1397)
			(layers "B.Cu" "B.Mask" "B.Paste")
			(net "RMII0_BMC_C_RX_ER")
			(options
				(clearance outline)
				(anchor circle)
			)
			(primitives
				(gr_poly
					(pts
						(arc
							(start -0.1778 0.2794)
							(mid -0.249642 0.249642)
							(end -0.2794 0.1778)
						)
						(arc
							(start -0.2794 -0.1778)
							(mid -0.249642 -0.249642)
							(end -0.1778 -0.2794)
						)
						(arc
							(start 0.1778 -0.2794)
							(mid 0.249642 -0.249642)
							(end 0.2794 -0.1778)
						)
						(arc
							(start 0.2794 0.1778)
							(mid 0.249642 0.249642)
							(end 0.1778 0.2794)
						)
					)
					(width 0)
					(fill yes)
				)
			)
		)
	)
	(footprint ""
		(layer "B.Cu")
		(at 124.403612 -213.36 90)
		(property "Reference" "SR911"
			(at 0 0 90)
			(layer "B.SilkS")
			(hide yes)
			(effects
				(font
					(size 1.27 1.27)
				)
				(justify mirror)
			)
		)
		(property "Value" "4K7R2F-GP"
			(at -0.064008 -3.993896 90)
			(unlocked yes)
			(layer "B.Fab")
			(hide yes)
			(effects
				(font
					(size 1.016 1.016)
					(thickness 0.1524)
				)
				(justify mirror)
			)
		)
		(property "Device Type" "R402H16"
			(at -0.064008 -5.517896 90)
			(unlocked yes)
			(layer "B.Fab")
			(hide yes)
			(effects
				(font
					(size 1.016 1.016)
					(thickness 0.1524)
				)
				(justify mirror)
			)
		)
		(duplicate_pad_numbers_are_jumpers no)
		(fp_line
			(start 0.508 -0.9398)
			(end 0.508 0.9398)
			(stroke
				(width 0.1524)
				(type default)
			)
			(layer "B.SilkS")
		)
		(fp_line
			(start -0.508 -0.9398)
			(end 0.508 -0.9398)
			(stroke
				(width 0.1524)
				(type default)
			)
			(layer "B.SilkS")
		)
		(fp_rect
			(start 0.508 0.9398)
			(end -0.508 -0.9398)
			(stroke
				(width 0)
				(type default)
			)
			(fill no)
			(layer "B.CrtYd")
		)
		(fp_rect
			(start 0.508 0.9398)
			(end -0.508 -0.9398)
			(stroke
				(width 0)
				(type default)
			)
			(fill no)
			(layer "B.Fab")
		)
		(pad "1" smd custom
			(at 0 -0.4445 270)
			(size 0.1397 0.1397)
			(layers "B.Cu" "B.Mask" "B.Paste")
			(net "REDV_I2C_SEL2A")
			(options
				(clearance outline)
				(anchor circle)
			)
			(primitives
				(gr_poly
					(pts
						(arc
							(start -0.1778 0.2794)
							(mid -0.249642 0.249642)
							(end -0.2794 0.1778)
						)
						(arc
							(start -0.2794 -0.1778)
							(mid -0.249642 -0.249642)
							(end -0.1778 -0.2794)
						)
						(arc
							(start 0.1778 -0.2794)
							(mid 0.249642 -0.249642)
							(end 0.2794 -0.1778)
						)
						(arc
							(start 0.2794 0.1778)
							(mid 0.249642 0.249642)
							(end 0.1778 0.2794)
						)
					)
					(width 0)
					(fill yes)
				)
			)
		)
		(pad "2" smd custom
			(at 0 0.4445 270)
			(size 0.1397 0.1397)
			(layers "B.Cu" "B.Mask" "B.Paste")
			(net "GND")
			(options
				(clearance outline)
				(anchor circle)
			)
			(primitives
				(gr_poly
					(pts
						(arc
							(start -0.1778 0.2794)
							(mid -0.249642 0.249642)
							(end -0.2794 0.1778)
						)
						(arc
							(start -0.2794 -0.1778)
							(mid -0.249642 -0.249642)
							(end -0.1778 -0.2794)
						)
						(arc
							(start 0.1778 -0.2794)
							(mid 0.249642 -0.249642)
							(end 0.2794 -0.1778)
						)
						(arc
							(start 0.2794 0.1778)
							(mid 0.249642 0.249642)
							(end 0.1778 0.2794)
						)
					)
					(width 0)
					(fill yes)
				)
			)
		)
	)
	(footprint ""
		(layer "B.Cu")
		(at 114.014504 -49.59985)
		(property "Reference" "STP160"
			(at 0 0 0)
			(layer "B.SilkS")
			(hide yes)
			(effects
				(font
					(size 1.27 1.27)
				)
				(justify mirror)
			)
		)
		(property "Value" "TPAD28"
			(at -0.0127 -1.8034 0)
			(unlocked yes)
			(layer "B.Fab")
			(hide yes)
			(effects
				(font
					(size 1.016 1.016)
					(thickness 0.1524)
				)
				(justify mirror)
			)
		)
		(property "Device Type" "TPAD28"
			(at -0.0127 -3.3274 0)
			(unlocked yes)
			(layer "B.Fab")
			(hide yes)
			(effects
				(font
					(size 1.016 1.016)
					(thickness 0.1524)
				)
				(justify mirror)
			)
		)
		(duplicate_pad_numbers_are_jumpers no)
		(fp_poly
			(pts
				(arc
					(start 0.3556 0)
					(mid -0.3556 0)
					(end 0.3556 0)
				)
			)
			(stroke
				(width 0)
				(type default)
			)
			(fill no)
			(layer "B.CrtYd")
		)
		(fp_poly
			(pts
				(arc
					(start 0.6096 0)
					(mid -0.6096 0)
					(end 0.6096 0)
				)
			)
			(stroke
				(width 0)
				(type default)
			)
			(fill no)
			(layer "B.Fab")
		)
		(pad "1" smd circle
			(at 0 0 180)
			(size 0.7112 0.7112)
			(layers "B.Cu" "B.Mask" "B.Paste")
			(net "XM_ADDR_24")
		)
	)
)
